# BASEBOARD_FAB2 (Tioga Pass) — schematic parts with pin connectivity, parts 2364–2364 of 4751; source: Cadence DE-HDL packaged netlist (pstxprt.dat, pstxnet.dat, pstchip.dat)

J4A2  SCONN288_H44441004  SCONN  pkg PIP  page 51
  1  \12v\(1)  = P12V_NVDIMM_DEF
  2  VSS(93)  GROUND  = GND
  3  DQ(4)  BI  = M_E_DQ<5>
  4  VSS(92)  GROUND  = GND
  5  DQ(0)  BI  = M_E_DQ<1>
  6  VSS(91)  GROUND  = GND
  7  DQS9P  BI  = M_E_DQS_DP<9>
  8  DQS9N  BI  = M_E_DQS_DN<9>
  9  VSS(90)  GROUND  = GND
  10  DQ(6)  BI  = M_E_DQ<7>
  11  VSS(89)  GROUND  = GND
  12  DQ(2)  BI  = M_E_DQ<3>
  13  VSS(88)  GROUND  = GND
  14  DQ(12)  BI  = M_E_DQ<13>
  15  VSS(87)  GROUND  = GND
  16  DQ(8)  BI  = M_E_DQ<9>
  17  VSS(86)  GROUND  = GND
  18  DQS10P  BI  = M_E_DQS_DP<10>
  19  DQS10N  BI  = M_E_DQS_DN<10>
  20  VSS(85)  GROUND  = GND
  21  DQ(14)  BI  = M_E_DQ<15>
  22  VSS(84)  GROUND  = GND
  23  DQ(10)  BI  = M_E_DQ<11>
  24  VSS(83)  GROUND  = GND
  25  DQ(20)  BI  = M_E_DQ<21>
  26  VSS(82)  GROUND  = GND
  27  DQ(16)  BI  = M_E_DQ<17>
  28  VSS(81)  GROUND  = GND
  29  DQS11P  BI  = M_E_DQS_DP<11>
  30  DQS11N  BI  = M_E_DQS_DN<11>
  31  VSS(80)  GROUND  = GND
  32  DQ(22)  BI  = M_E_DQ<23>
  33  VSS(79)  GROUND  = GND
  34  DQ(18)  BI  = M_E_DQ<19>
  35  VSS(78)  GROUND  = GND
  36  DQ(28)  BI  = M_E_DQ<29>
  37  VSS(77)  GROUND  = GND
  38  DQ(24)  BI  = M_E_DQ<25>
  39  VSS(76)  GROUND  = GND
  40  DQS12P  BI  = M_E_DQS_DP<12>
  41  DQS12N  BI  = M_E_DQS_DN<12>
  42  VSS(75)  GROUND  = GND
  43  DQ(30)  BI  = M_E_DQ<31>
  44  VSS(74)  GROUND  = GND
  45  DQ(26)  BI  = M_E_DQ<27>
  46  VSS(73)  GROUND  = GND
  47  CB(4)  BI  = M_E_ECC<5>
  48  VSS(72)  GROUND  = GND
  49  CB(0)  BI  = M_E_ECC<1>
  50  VSS(71)  GROUND  = GND
  51  DQS17P  BI  = M_E_DQS_DP<17>
  52  DQS17N  BI  = M_E_DQS_DN<17>
  53  VSS(70)  GROUND  = GND
  54  CB(6)  BI  = M_E_ECC<7>
  55  VSS(69)  GROUND  = GND
  56  CB(2)  BI  = M_E_ECC<3>
  57  VSS(68)  GROUND  = GND
  58  RESET_N  BI  = M_DEF_RST_N
  59  VDD(25)  POWER  = PVDDQ_DEF
  60  CKE(0)  BI  = M_E_CKE<0>
  61  VDD(24)  POWER  = PVDDQ_DEF
  62  ACT_N  BI  = M_E_ACT_N
  63  BG(0)  BI  = M_E_BG<0>
  64  VDD(23)  POWER  = PVDDQ_DEF
  65  A12  BI  = M_E_MA<12>
  66  A9  BI  = M_E_MA<9>
  67  VDD(22)  POWER  = PVDDQ_DEF
  68  A8  BI  = M_E_MA<8>
  69  A6  BI  = M_E_MA<6>
  70  VDD(21)  POWER  = PVDDQ_DEF
  71  A3  BI  = M_E_MA<3>
  72  A1  BI  = M_E_MA<1>
  73  VDD(20)  POWER  = PVDDQ_DEF
  74  CK0P  BI  = M_E_CLK_DP<0>
  75  CK0N  BI  = M_E_CLK_DN<0>
  76  VDD(19)  POWER  = PVDDQ_DEF
  77  VTT(1)  POWER  = PVTT_DEF
  78  EVENT_N  BI  = FM_DIMM_EVENT_COD_N
  79  A0  BI  = M_E_MA<0>
  80  VDD(18)  POWER  = PVDDQ_DEF
  81  BA(0)  BI  = M_E_BA<0>
  82  A16_RAS_N  BI  = M_E_MA<16>
  83  VDD(17)  POWER  = PVDDQ_DEF
  84  S0_N  BI  = M_E_CS_N<0>
  85  VDD(16)  POWER  = PVDDQ_DEF
  86  A15_CAS_N  BI  = M_E_MA<15>
  87  ODT(0)  BI  = M_E_ODT<0>
  88  VDD(15)  POWER  = PVDDQ_DEF
  89  S1_N  BI  = M_E_CS_N<1>
  90  VDD(14)  POWER  = PVDDQ_DEF
  91  ODT(1)  BI  = M_E_ODT<1>
  92  VDD(13)  POWER  = PVDDQ_DEF
  93  S2_N_C(0)  BI  = M_E_CS_N<2>
  94  VSS(67)  GROUND  = GND
  95  DQ(36)  BI  = M_E_DQ<37>
  96  VSS(66)  GROUND  = GND
  97  DQ(32)  BI  = M_E_DQ<33>
  98  VSS(65)  GROUND  = GND
  99  DQS13P  BI  = M_E_DQS_DP<13>
  100  DQS13N  BI  = M_E_DQS_DN<13>
  101  VSS(64)  GROUND  = GND
  102  DQ(38)  BI  = M_E_DQ<39>
  103  VSS(63)  GROUND  = GND
  104  DQ(34)  BI  = M_E_DQ<35>
  105  VSS(62)  GROUND  = GND
  106  DQ(44)  BI  = M_E_DQ<45>
  107  VSS(61)  GROUND  = GND
  108  DQ(40)  BI  = M_E_DQ<41>
  109  VSS(60)  GROUND  = GND
  110  DQS14P  BI  = M_E_DQS_DP<14>
  111  DQS14N  BI  = M_E_DQS_DN<14>
  112  VSS(59)  GROUND  = GND
  113  DQ(46)  BI  = M_E_DQ<47>
  114  VSS(58)  GROUND  = GND
  115  DQ(42)  BI  = M_E_DQ<43>
  116  VSS(57)  GROUND  = GND
  117  DQ(52)  BI  = M_E_DQ<53>
  118  VSS(56)  GROUND  = GND
  119  DQ(48)  BI  = M_E_DQ<49>
  120  VSS(55)  GROUND  = GND
  121  DQS15P  BI  = M_E_DQS_DP<15>
  122  DQS15N  BI  = M_E_DQS_DN<15>
  123  VSS(54)  GROUND  = GND
  124  DQ(54)  BI  = M_E_DQ<55>
  125  VSS(53)  GROUND  = GND
  126  DQ(50)  BI  = M_E_DQ<51>
  127  VSS(52)  GROUND  = GND
  128  DQ(60)  BI  = M_E_DQ<61>
  129  VSS(51)  GROUND  = GND
  130  DQ(56)  BI  = M_E_DQ<57>
  131  VSS(50)  GROUND  = GND
  132  DQS16P  BI  = M_E_DQS_DP<16>
  133  DQS16N  BI  = M_E_DQS_DN<16>
  134  VSS(49)  GROUND  = GND
  135  DQ(62)  BI  = M_E_DQ<63>
  136  VSS(48)  GROUND  = GND
  137  DQ(58)  BI  = M_E_DQ<59>
  138  VSS(47)  GROUND  = GND
  139  SA(0)  BI  = GND
  140  SA(1)  BI  = PVPP_DEF
  141  SCL  BI  = SMB_DDR_DEF_VPP_SCL
  142  VPP(4)  POWER  = PVPP_DEF
  143  VPP(3)  POWER  = PVPP_DEF
  144  RFU(2)  BI  = TP_CH_E_DIMM_E0_RFU_2
  145  \12v\(0)  = P12V_NVDIMM_DEF
  146  VREFCA  BI  = M_E_VREF
  147  VSS(46)  GROUND  = GND
  148  DQ(5)  BI  = M_E_DQ<4>
  149  VSS(45)  GROUND  = GND
  150  DQ(1)  BI  = M_E_DQ<0>
  151  VSS(44)  GROUND  = GND
  152  DQS0N  BI  = M_E_DQS_DN<0>
  153  DQS0P  BI  = M_E_DQS_DP<0>
  154  VSS(43)  GROUND  = GND
  155  DQ(7)  BI  = M_E_DQ<6>
  156  VSS(42)  GROUND  = GND
  157  DQ(3)  BI  = M_E_DQ<2>
  158  VSS(41)  GROUND  = GND
  159  DQ(13)  BI  = M_E_DQ<12>
  160  VSS(40)  GROUND  = GND
  161  DQ(9)  BI  = M_E_DQ<8>
  162  VSS(39)  GROUND  = GND
  163  DQS1N  BI  = M_E_DQS_DN<1>
  164  DQS1P  BI  = M_E_DQS_DP<1>
  165  VSS(38)  GROUND  = GND
  166  DQ(15)  BI  = M_E_DQ<14>
  167  VSS(37)  GROUND  = GND
  168  DQ(11)  BI  = M_E_DQ<10>
  169  VSS(36)  GROUND  = GND
  170  DQ(21)  BI  = M_E_DQ<20>
  171  VSS(35)  GROUND  = GND
  172  DQ(17)  BI  = M_E_DQ<16>
  173  VSS(34)  GROUND  = GND
  174  DQS2N  BI  = M_E_DQS_DN<2>
  175  DQS2P  BI  = M_E_DQS_DP<2>
  176  VSS(33)  GROUND  = GND
  177  DQ(23)  BI  = M_E_DQ<22>
  178  VSS(32)  GROUND  = GND
  179  DQ(19)  BI  = M_E_DQ<18>
  180  VSS(31)  GROUND  = GND
  181  DQ(29)  BI  = M_E_DQ<28>
  182  VSS(30)  GROUND  = GND
  183  DQ(25)  BI  = M_E_DQ<24>
  184  VSS(29)  GROUND  = GND
  185  DQS3N  BI  = M_E_DQS_DN<3>
  186  DQS3P  BI  = M_E_DQS_DP<3>
  187  VSS(28)  GROUND  = GND
  188  DQ(31)  BI  = M_E_DQ<30>
  189  VSS(27)  GROUND  = GND
  190  DQ(27)  BI  = M_E_DQ<26>
  191  VSS(26)  GROUND  = GND
  192  CB(5)  BI  = M_E_ECC<4>
  193  VSS(25)  GROUND  = GND
  194  CB(1)  BI  = M_E_ECC<0>
  195  VSS(24)  GROUND  = GND
  196  DQS8N  BI  = M_E_DQS_DN<8>
  197  DQS8P  BI  = M_E_DQS_DP<8>
  198  VSS(23)  GROUND  = GND
  199  CB(7)  BI  = M_E_ECC<6>
  200  VSS(22)  GROUND  = GND
  201  CB(3)  BI  = M_E_ECC<2>
  202  VSS(21)  GROUND  = GND
  203  CKE(1)  BI  = M_E_CKE<1>
  204  VDD(12)  POWER  = PVDDQ_DEF
  205  RFU(0)  BI  = TP_CH_E_DIMM_E0_RFU_0
  206  VDD(11)  POWER  = PVDDQ_DEF
  207  BG(1)  BI  = M_E_BG<1>
  208  ALERT_N  BI  = M_E_ALERT_N
  209  VDD(10)  POWER  = PVDDQ_DEF
  210  A11  BI  = M_E_MA<11>
  211  A7  BI  = M_E_MA<7>
  212  VDD(9)  POWER  = PVDDQ_DEF
  213  A5  BI  = M_E_MA<5>
  214  A4  BI  = M_E_MA<4>
  215  VDD(8)  POWER  = PVDDQ_DEF
  216  A2  BI  = M_E_MA<2>
  217  VDD(7)  POWER  = PVDDQ_DEF
  218  CK1P  BI  = M_E_CLK_DP<1>
  219  CK1N  BI  = M_E_CLK_DN<1>
  220  VDD(6)  POWER  = PVDDQ_DEF
  221  VTT(0)  POWER  = PVTT_DEF
  222  PAR  BI  = M_E_PAR
  223  VDD(5)  POWER  = PVDDQ_DEF
  224  BA(1)  BI  = M_E_BA<1>
  225  A10  BI  = M_E_MA<10>
  226  VDD(4)  POWER  = PVDDQ_DEF
  227  RFU(1)  BI  = TP_CH_E_DIMM_E0_RFU_1
  228  A14_WE_N  BI  = M_E_MA<14>
  229  VDD(3)  POWER  = PVDDQ_DEF
  230  SAVE_N_NC  BI  = FM_ADR_COMPLETE_DEF_N
  231  VDD(2)  POWER  = PVDDQ_DEF
  232  A13  BI  = M_E_MA<13>
  233  VDD(1)  POWER  = PVDDQ_DEF
  234  A17  BI  = M_E_MA<17>
  235  C(2)  BI  = M_E_C<2>
  236  VDD(0)  POWER  = PVDDQ_DEF
  237  S3_N_C(1)  BI  = M_E_CS_N<3>
  238  SA(2)  BI  = GND
  239  VSS(20)  GROUND  = GND
  240  DQ(37)  BI  = M_E_DQ<36>
  241  VSS(19)  GROUND  = GND
  242  DQ(33)  BI  = M_E_DQ<32>
  243  VSS(18)  GROUND  = GND
  244  DQS4N  BI  = M_E_DQS_DN<4>
  245  DQS4P  BI  = M_E_DQS_DP<4>
  246  VSS(17)  GROUND  = GND
  247  DQ(39)  BI  = M_E_DQ<38>
  248  VSS(16)  GROUND  = GND
  249  DQ(35)  BI  = M_E_DQ<34>
  250  VSS(15)  GROUND  = GND
  251  DQ(45)  BI  = M_E_DQ<44>
  252  VSS(14)  GROUND  = GND
  253  DQ(41)  BI  = M_E_DQ<40>
  254  VSS(13)  GROUND  = GND
  255  DQS5N  BI  = M_E_DQS_DN<5>
  256  DQS5P  BI  = M_E_DQS_DP<5>
  257  VSS(12)  GROUND  = GND
  258  DQ(47)  BI  = M_E_DQ<46>
  259  VSS(11)  GROUND  = GND
  260  DQ(43)  BI  = M_E_DQ<42>
  261  VSS(10)  GROUND  = GND
  262  DQ(53)  BI  = M_E_DQ<52>
  263  VSS(9)  GROUND  = GND
  264  DQ(49)  BI  = M_E_DQ<48>
  265  VSS(8)  GROUND  = GND
  266  DQS6N  BI  = M_E_DQS_DN<6>
  267  DQS6P  BI  = M_E_DQS_DP<6>
  268  VSS(7)  GROUND  = GND
  269  DQ(55)  BI  = M_E_DQ<54>
  270  VSS(6)  GROUND  = GND
  271  DQ(51)  BI  = M_E_DQ<50>
  272  VSS(5)  GROUND  = GND
  273  DQ(61)  BI  = M_E_DQ<60>
  274  VSS(4)  GROUND  = GND
  275  DQ(57)  BI  = M_E_DQ<56>
  276  VSS(3)  GROUND  = GND
  277  DQS7N  BI  = M_E_DQS_DN<7>
  278  DQS7P  BI  = M_E_DQS_DP<7>
  279  VSS(2)  GROUND  = GND
  280  DQ(63)  BI  = M_E_DQ<62>
  281  VSS(1)  GROUND  = GND
  282  DQ(59)  BI  = M_E_DQ<58>
  283  VSS(0)  GROUND  = GND
  284  VDDSPD  BI  = PVPP_DEF
  285  SDA  BI  = SMB_DDR_DEF_VPP_SDA
  286  VPP(1)  POWER  = PVPP_DEF
  287  VPP(0)  POWER  = PVPP_DEF
  288  VPP(2)  POWER  = PVPP_DEF
